# ZAIUS-LV CARD-DVT-X01-BOM-X00_20170420_Final.xls.xlsx — PWA BOM (bom)
| FOXCONN TECHNOLOGY GROUP |  |  |  |  |  |  |  |  |  |  |  |  |  |  |  |  |  |  |  |
| BILL OF MATERIAL |  |  |  |  |  |  |  |  |  |  |  |  |  |  |  |  |  |  |  |
| REV OF  BOM | X00 | CUSTOMER |  | Customer |  | CUSTOMER P/N |  | PWA P/N： | PWA DESCRIPTION |  |  |  | PRODUCT CODE |  |  | PWA  REV | X01 | DATE | 42845 |
| Sourcing (Single/Sole/Multi) | Critical Commodity (Y or N) | Component Class (1, 2, other) | Customer PSL (Y or N) | Line Item | Item Number | Foxconn P/N | Customer P/N | Part Description | Manufacturer  Full Name | Manufacturer  Part Number | Qty | RoHS Status | Location | CC Qual Build: | Qual by (Customer / ODM ?) | The Date of Change Part or Add 2nd Source | Configuration Identifier | Customer Comments | ODM Comments |
| Single |  |  |  | 1 | 1 | 0101EW900-000-G |  | PCB,Zaius-LV Card DVT-X01,OSP,Blu,4L,1.5925*0.9953,G | GOLD CIRCUIT ELECTRONICS LTD. | 0101EW900-000-G | 1 |  | PCB |  |  |  |  |  |  |
| Multi | N | ND | N | 2 | 2 | 610107A00-017-G | - | RES,0 Ohm,+/-5%,1/16W,G,SMD0402 | KOA SPEER ELECTRONICS, INC. | RK73Z1ETTP | 1 | N | R2 |  |  |  |  |  |  |
|  |  |  |  |  | 2 | 610107A00-024-G |  | RES,0 Ohm,+/-5%,1/16W,G,SMD0402 | PANASONIC INDUSTRIAL CO.,LTD. | ERJ2GE0R00X |  |  |  |  |  |  |  |  |  |
|  |  |  |  |  | 2 | 610107A00-029-G |  | RES,0 Ohm,+/-5%,1/16W,G,SMD0402 | VISHAY ENTER TECHNO LOGY.INC | CRCW04020000Z0ED |  |  |  |  |  |  |  |  |  |
| Single | Y |  | N | 3 | 3 | 34131N000-G78-G |  | CONN,BTB,V/T,0.8mm,8u,G,SMD-80 | FCI CONNECTORS HONGKONG LTD. | 61083-081402LF | 2 |  | J1,J2 |  |  |  |  |  |  |
